# T6G (Grand Teton) — schematic netlist excerpt (pin names and nets, part order shuffled) for the footprints in the layout excerpt that follows; sources: Cadence DE-HDL packaged netlist, KiCad conversion of 04192023_DAF0TMB3IC0_F0TG_MB_C_brd_V02_OCP.brd

C42  Q_CAP  0.1UF 25V 10% X7R  pkg 0402  page 34 : A = PVDD18_S5_P0 ; B = GND
PR151  Q_RES  1K 1% EMPTY  pkg 0402LF  page 210 : A = PVDD18_S5_P1 ; B = SVID_PVDDCR_CPU0_P1_SVTI

(kicad_pcb
	(version 20260206)
	(generator "pcbnew")
	(generator_version "10.0")
	(general
		(thickness 1.6)
		(legacy_teardrops no)
	)
	(paper "A4")
	(title_block
		(title "04192023_DAF0TMB3IC0_F0TG_MB_C_brd_V02_OCP.brd")
		(comment 1 "Grand Teton / footprints 3575-3576 of 8354")
	)
	(layers
		(0 "F.Cu" signal "TOP")
		(4 "In1.Cu" signal "GND")
		(6 "In2.Cu" signal "IN1")
		(8 "In3.Cu" signal "GND1")
		(10 "In4.Cu" signal "IN2")
		(12 "In5.Cu" signal "GND2")
		(14 "In6.Cu" signal "IN3")
		(16 "In7.Cu" signal "GND3")
		(18 "In8.Cu" signal "VCC")
		(20 "In9.Cu" signal "VCC1")
		(22 "In10.Cu" signal "GND4")
		(24 "In11.Cu" signal "IN4")
		(26 "In12.Cu" signal "GND5")
		(28 "In13.Cu" signal "IN5")
		(30 "In14.Cu" signal "GND6")
		(32 "In15.Cu" signal "IN6")
		(34 "In16.Cu" signal "GND7")
		(2 "B.Cu" signal "BOTTOM")
		(9 "F.Adhes" user "F.Adhesive")
		(11 "B.Adhes" user "B.Adhesive")
		(13 "F.Paste" user "Package Geometry/Pastemask Top")
		(15 "B.Paste" user "Package Geometry/Pastemask Bottom")
		(5 "F.SilkS" user "Ref Des/Silkscreen Top")
		(7 "B.SilkS" user "Ref Des/Silkscreen Bottom")
		(1 "F.Mask" user "Board Geometry/Soldermask Top")
		(3 "B.Mask" user "Board Geometry/Soldermask Bottom")
		(17 "Dwgs.User" user "User.Drawings")
		(19 "Cmts.User" user "User.Comments")
		(21 "Eco1.User" user "User.Eco1")
		(23 "Eco2.User" user "User.Eco2")
		(25 "Edge.Cuts" user "Board Geometry/Outline")
		(27 "Margin" user)
		(31 "F.CrtYd" user "Package Geometry/Place Bound Top")
		(29 "B.CrtYd" user "Package Geometry/Place Bound Bottom")
		(35 "F.Fab" user "Ref Des/Assembly Top")
		(33 "B.Fab" user "Ref Des/Assembly Bottom")
	)
	(footprint ""
		(layer "F.Cu")
		(at 90.819478 -149.96541 180)
		(property "Reference" "PR151"
			(at 0 0 180)
			(layer "F.SilkS")
			(hide yes)
			(effects
				(font
					(size 1.27 1.27)
				)
			)
		)
		(property "Value" ""
			(at 0 0 180)
			(layer "F.Fab")
			(effects
				(font
					(size 1.27 1.27)
				)
			)
		)
		(duplicate_pad_numbers_are_jumpers no)
		(fp_line
			(start 0.7874 0.4064)
			(end -0.7874 0.4064)
			(stroke
				(width 0.1524)
				(type default)
			)
			(layer "F.SilkS")
		)
		(fp_line
			(start 0.7874 -0.4064)
			(end 0.7874 0.4064)
			(stroke
				(width 0.1524)
				(type default)
			)
			(layer "F.SilkS")
		)
		(fp_line
			(start -0.7874 0.4064)
			(end -0.7874 -0.4064)
			(stroke
				(width 0.1524)
				(type default)
			)
			(layer "F.SilkS")
		)
		(fp_line
			(start -0.7874 -0.4064)
			(end 0.7874 -0.4064)
			(stroke
				(width 0.1524)
				(type default)
			)
			(layer "F.SilkS")
		)
		(fp_line
			(start 0.67945 0.3048)
			(end 0.120396 0.3048)
			(stroke
				(width 0.1)
				(type default)
			)
			(layer "F.Fab")
		)
		(fp_line
			(start 0.67945 -0.3048)
			(end 0.67945 0.3048)
			(stroke
				(width 0.1)
				(type default)
			)
			(layer "F.Fab")
		)
		(fp_line
			(start 0.12065 -0.2794)
			(end 0.12065 -0.3048)
			(stroke
				(width 0.1)
				(type default)
			)
			(layer "F.Fab")
		)
		(fp_line
			(start 0.12065 -0.3048)
			(end 0.67945 -0.3048)
			(stroke
				(width 0.1)
				(type default)
			)
			(layer "F.Fab")
		)
		(fp_line
			(start 0.120396 0.3048)
			(end 0.120396 0.2794)
			(stroke
				(width 0.1)
				(type default)
			)
			(layer "F.Fab")
		)
		(fp_line
			(start 0.120396 0.2794)
			(end -0.12065 0.2794)
			(stroke
				(width 0.1)
				(type default)
			)
			(layer "F.Fab")
		)
		(fp_line
			(start -0.12065 0.3048)
			(end -0.67945 0.3048)
			(stroke
				(width 0.1)
				(type default)
			)
			(layer "F.Fab")
		)
		(fp_line
			(start -0.12065 0.2794)
			(end -0.12065 0.3048)
			(stroke
				(width 0.1)
				(type default)
			)
			(layer "F.Fab")
		)
		(fp_line
			(start -0.12065 -0.2794)
			(end 0.12065 -0.2794)
			(stroke
				(width 0.1)
				(type default)
			)
			(layer "F.Fab")
		)
		(fp_line
			(start -0.12065 -0.305054)
			(end -0.12065 -0.2794)
			(stroke
				(width 0.1)
				(type default)
			)
			(layer "F.Fab")
		)
		(fp_line
			(start -0.67945 0.3048)
			(end -0.67945 -0.305054)
			(stroke
				(width 0.1)
				(type default)
			)
			(layer "F.Fab")
		)
		(fp_line
			(start -0.67945 -0.305054)
			(end -0.12065 -0.305054)
			(stroke
				(width 0.1)
				(type default)
			)
			(layer "F.Fab")
		)
		(pad "1" smd circle
			(at -0.40005 0 180)
			(size 0 0)
			(layers "F.Cu" "F.Mask" "F.Paste")
			(net "PVDD18_S5_P1")
		)
		(pad "2" smd circle
			(at 0.40005 0 180)
			(size 0 0)
			(layers "F.Cu" "F.Mask" "F.Paste")
			(net "SVID_PVDDCR_CPU0_P1_SVTI")
		)
	)
	(footprint ""
		(layer "F.Cu")
		(at 180.824378 -153.632662 -90)
		(property "Reference" "C42"
			(at 0 0 270)
			(layer "F.SilkS")
			(hide yes)
			(effects
				(font
					(size 1.27 1.27)
				)
			)
		)
		(property "Value" ""
			(at 0 0 270)
			(layer "F.Fab")
			(effects
				(font
					(size 1.27 1.27)
				)
			)
		)
		(duplicate_pad_numbers_are_jumpers no)
		(fp_line
			(start -0.7874 0.4064)
			(end -0.7874 -0.4064)
			(stroke
				(width 0.1524)
				(type default)
			)
			(layer "F.SilkS")
		)
		(fp_line
			(start 0.7874 0.4064)
			(end -0.7874 0.4064)
			(stroke
				(width 0.1524)
				(type default)
			)
			(layer "F.SilkS")
		)
		(fp_line
			(start -0.7874 -0.4064)
			(end 0.7874 -0.4064)
			(stroke
				(width 0.1524)
				(type default)
			)
			(layer "F.SilkS")
		)
		(fp_line
			(start 0.7874 -0.4064)
			(end 0.7874 0.4064)
			(stroke
				(width 0.1524)
				(type default)
			)
			(layer "F.SilkS")
		)
		(fp_line
			(start -0.67945 0.3048)
			(end -0.67945 -0.305054)
			(stroke
				(width 0.1)
				(type default)
			)
			(layer "F.Fab")
		)
		(fp_line
			(start -0.12065 0.3048)
			(end -0.67945 0.3048)
			(stroke
				(width 0.1)
				(type default)
			)
			(layer "F.Fab")
		)
		(fp_line
			(start 0.120396 0.3048)
			(end 0.120396 0.2794)
			(stroke
				(width 0.1)
				(type default)
			)
			(layer "F.Fab")
		)
		(fp_line
			(start 0.67945 0.3048)
			(end 0.120396 0.3048)
			(stroke
				(width 0.1)
				(type default)
			)
			(layer "F.Fab")
		)
		(fp_line
			(start -0.12065 0.2794)
			(end -0.12065 0.3048)
			(stroke
				(width 0.1)
				(type default)
			)
			(layer "F.Fab")
		)
		(fp_line
			(start 0.120396 0.2794)
			(end -0.12065 0.2794)
			(stroke
				(width 0.1)
				(type default)
			)
			(layer "F.Fab")
		)
		(fp_line
			(start -0.12065 -0.2794)
			(end 0.12065 -0.2794)
			(stroke
				(width 0.1)
				(type default)
			)
			(layer "F.Fab")
		)
		(fp_line
			(start 0.12065 -0.2794)
			(end 0.12065 -0.3048)
			(stroke
				(width 0.1)
				(type default)
			)
			(layer "F.Fab")
		)
		(fp_line
			(start 0.12065 -0.3048)
			(end 0.67945 -0.3048)
			(stroke
				(width 0.1)
				(type default)
			)
			(layer "F.Fab")
		)
		(fp_line
			(start 0.67945 -0.3048)
			(end 0.67945 0.3048)
			(stroke
				(width 0.1)
				(type default)
			)
			(layer "F.Fab")
		)
		(fp_line
			(start -0.67945 -0.305054)
			(end -0.12065 -0.305054)
			(stroke
				(width 0.1)
				(type default)
			)
			(layer "F.Fab")
		)
		(fp_line
			(start -0.12065 -0.305054)
			(end -0.12065 -0.2794)
			(stroke
				(width 0.1)
				(type default)
			)
			(layer "F.Fab")
		)
		(pad "1" smd circle
			(at -0.40005 0 270)
			(size 0 0)
			(layers "F.Cu" "F.Mask" "F.Paste")
			(net "PVDD18_S5_P0")
		)
		(pad "2" smd circle
			(at 0.40005 0 270)
			(size 0 0)
			(layers "F.Cu" "F.Mask" "F.Paste")
			(net "GND")
		)
	)
)
